(kicad_pcb
	(version 20241229)
	(generator "pcbnew")
	(generator_version "9.0")
	(general
		(thickness 1.61)
		(legacy_teardrops no)
	)
	(paper "A3")
	(title_block
		(title "SO-DIMM DDR5 Tester")
		(date "2025-11-26")
		(rev "1.3.0")
		(comment 9 "footprints 148-151 of 627")
	)
	(layers
		(0 "F.Cu" signal)
		(4 "In1.Cu" power)
		(6 "In2.Cu" mixed)
		(8 "In3.Cu" power)
		(10 "In4.Cu" mixed)
		(12 "In5.Cu" power)
		(14 "In6.Cu" mixed)
		(16 "In7.Cu" power)
		(18 "In8.Cu" power)
		(20 "In9.Cu" mixed)
		(22 "In10.Cu" power)
		(2 "B.Cu" signal)
		(9 "F.Adhes" user "F.Adhesive")
		(11 "B.Adhes" user "B.Adhesive")
		(13 "F.Paste" user)
		(15 "B.Paste" user)
		(5 "F.SilkS" user "F.Silkscreen")
		(7 "B.SilkS" user "B.Silkscreen")
		(1 "F.Mask" user)
		(3 "B.Mask" user)
		(17 "Dwgs.User" user "User.Drawings")
		(19 "Cmts.User" user "User.Comments")
		(21 "Eco1.User" user "User.Eco1")
		(23 "Eco2.User" user "User.Eco2")
		(25 "Edge.Cuts" user)
		(27 "Margin" user)
		(31 "F.CrtYd" user "F.Courtyard")
		(29 "B.CrtYd" user "B.Courtyard")
		(35 "F.Fab" user)
		(33 "B.Fab" user)
	)
	(footprint "antmicro-footprints:SC70-3"
		(layer "F.Cu")
		(at 86.350501 122.926 90)
		(property "Reference" "Q6"
			(at 0 -1.6 90)
			(layer "F.SilkS")
			(hide yes)
			(effects
				(font
					(size 0.7 0.7)
					(thickness 0.15)
				)
				(justify left bottom)
			)
		)
		(property "Value" "BSS138PW,115"
			(at 0 2.3 90)
			(layer "F.Fab")
			(effects
				(font
					(size 0.7 0.7)
					(thickness 0.15)
				)
				(justify left bottom)
			)
		)
		(property "Datasheet" "https://assets.nexperia.com/documents/data-sheet/BSS138PW.pdf"
			(at 0 0 90)
			(layer "F.Fab")
			(hide yes)
			(effects
				(font
					(size 1.27 1.27)
					(thickness 0.15)
				)
			)
		)
		(property "Description" "Power MOSFET, N Channel, 60 V, 320 mA, 0.9 ohm, SOT-323, Surface Mount"
			(at 0 0 90)
			(layer "F.Fab")
			(hide yes)
			(effects
				(font
					(size 1.27 1.27)
					(thickness 0.15)
				)
			)
		)
		(property "Author" "Antmicro"
			(at 209.276501 36.575499 0)
			(layer "F.Fab")
			(hide yes)
			(effects
				(font
					(size 1 1)
					(thickness 0.15)
				)
			)
		)
		(property "License" "Apache-2.0"
			(at 209.276501 36.575499 0)
			(layer "F.Fab")
			(hide yes)
			(effects
				(font
					(size 1 1)
					(thickness 0.15)
				)
			)
		)
		(property "MPN" "BSS138PW,115"
			(at 209.276501 36.575499 0)
			(layer "F.Fab")
			(hide yes)
			(effects
				(font
					(size 1 1)
					(thickness 0.15)
				)
			)
		)
		(property "Manufacturer" "Nexperia"
			(at 209.276501 36.575499 0)
			(layer "F.Fab")
			(hide yes)
			(effects
				(font
					(size 1 1)
					(thickness 0.15)
				)
			)
		)
		(sheetname "/FPGA bank 14/")
		(sheetfile "fpga-bank-14.kicad_sch")
		(attr smd)
		(fp_line
			(start -0.3 -1)
			(end 0.627 -0.999)
			(stroke
				(width 0.15)
				(type solid)
			)
			(layer "F.SilkS")
		)
		(fp_line
			(start 0.627 -0.6)
			(end 0.627 -0.999)
			(stroke
				(width 0.15)
				(type solid)
			)
			(layer "F.SilkS")
		)
		(fp_line
			(start 0.627 0.6)
			(end 0.627 1.001)
			(stroke
				(width 0.15)
				(type solid)
			)
			(layer "F.SilkS")
		)
		(fp_line
			(start -0.3 1)
			(end 0.627 1.001)
			(stroke
				(width 0.15)
				(type solid)
			)
			(layer "F.SilkS")
		)
		(fp_line
			(start 0.9 -1.3)
			(end 0.9 -0.4)
			(stroke
				(width 0.05)
				(type solid)
			)
			(layer "F.CrtYd")
		)
		(fp_line
			(start -0.9 -1.3)
			(end 0.9 -1.3)
			(stroke
				(width 0.05)
				(type solid)
			)
			(layer "F.CrtYd")
		)
		(fp_line
			(start -0.9 -1.3)
			(end -0.9 -1)
			(stroke
				(width 0.05)
				(type solid)
			)
			(layer "F.CrtYd")
		)
		(fp_line
			(start -0.9 -1)
			(end -1.4 -1)
			(stroke
				(width 0.05)
				(type solid)
			)
			(layer "F.CrtYd")
		)
		(fp_line
			(start 1.4 -0.4)
			(end 1.4 0.4)
			(stroke
				(width 0.05)
				(type solid)
			)
			(layer "F.CrtYd")
		)
		(fp_line
			(start 0.9 -0.4)
			(end 1.4 -0.4)
			(stroke
				(width 0.05)
				(type solid)
			)
			(layer "F.CrtYd")
		)
		(fp_line
			(start 1.4 0.4)
			(end 0.9 0.4)
			(stroke
				(width 0.05)
				(type solid)
			)
			(layer "F.CrtYd")
		)
		(fp_line
			(start 0.9 0.4)
			(end 0.9 1.3)
			(stroke
				(width 0.05)
				(type solid)
			)
			(layer "F.CrtYd")
		)
		(fp_line
			(start -0.9 1)
			(end -1.4 1)
			(stroke
				(width 0.05)
				(type solid)
			)
			(layer "F.CrtYd")
		)
		(fp_line
			(start -1.4 1)
			(end -1.4 -1)
			(stroke
				(width 0.05)
				(type solid)
			)
			(layer "F.CrtYd")
		)
		(fp_line
			(start 0.9 1.3)
			(end -0.9 1.3)
			(stroke
				(width 0.05)
				(type solid)
			)
			(layer "F.CrtYd")
		)
		(fp_line
			(start -0.9 1.3)
			(end -0.9 1)
			(stroke
				(width 0.05)
				(type solid)
			)
			(layer "F.CrtYd")
		)
		(fp_rect
			(start -0.623 -0.999)
			(end 0.627 1.001)
			(stroke
				(width 0.15)
				(type solid)
			)
			(fill no)
			(layer "F.Fab")
		)
		(pad "1" smd rect
			(at -1.051 -0.65 180)
			(size 0.6 0.6)
			(layers "F.Cu" "F.Mask" "F.Paste")
			(net 619 "/FPGA bank 14/USR_LED2")
			(pinfunction "G")
			(pintype "input")
		)
		(pad "2" smd rect
			(at -1.051 0.65 180)
			(size 0.6 0.6)
			(layers "F.Cu" "F.Mask" "F.Paste")
			(net 1 "GND")
			(pinfunction "S")
			(pintype "passive")
		)
		(pad "3" smd rect
			(at 1.05 0 180)
			(size 0.6 0.6)
			(layers "F.Cu" "F.Mask" "F.Paste")
			(net 355 "Net-(Q6-D)")
			(pinfunction "D")
			(pintype "passive")
		)
	)
	(footprint "antmicro-footprints:C_0603_1608Metric"
		(layer "F.Cu")
		(at 191.245501 182.923 90)
		(descr "Capacitor SMD 0603")
		(tags "capacitor 0603")
		(property "Reference" "C187"
			(at -1.42757 -1.000252 90)
			(layer "F.SilkS")
			(hide yes)
			(effects
				(font
					(size 0.7 0.7)
					(thickness 0.15)
				)
				(justify left bottom)
			)
		)
		(property "Value" "C_22u_0603"
			(at -1.42757 1.770288 90)
			(layer "F.Fab")
			(effects
				(font
					(size 0.7 0.7)
					(thickness 0.15)
				)
				(justify left bottom)
			)
		)
		(property "Datasheet" "https://www.murata.com/products/productdetail?partno=GRM188R60J226MEA0%23"
			(at 0 0 90)
			(layer "F.Fab")
			(hide yes)
			(effects
				(font
					(size 1.27 1.27)
					(thickness 0.15)
				)
			)
		)
		(property "Author" "Antmicro"
			(at 374.168501 -8.322501 0)
			(layer "F.Fab")
			(hide yes)
			(effects
				(font
					(size 1 1)
					(thickness 0.15)
				)
			)
		)
		(property "Dielectric" ""
			(at 374.168501 -8.322501 0)
			(layer "F.Fab")
			(hide yes)
			(effects
				(font
					(size 1 1)
					(thickness 0.15)
				)
			)
		)
		(property "License" "Apache-2.0"
			(at 374.168501 -8.322501 0)
			(layer "F.Fab")
			(hide yes)
			(effects
				(font
					(size 1 1)
					(thickness 0.15)
				)
			)
		)
		(property "MPN" "GRM188R60J226MEA0D"
			(at 374.168501 -8.322501 0)
			(layer "F.Fab")
			(hide yes)
			(effects
				(font
					(size 1 1)
					(thickness 0.15)
				)
			)
		)
		(property "Manufacturer" "Murata"
			(at 374.168501 -8.322501 0)
			(layer "F.Fab")
			(hide yes)
			(effects
				(font
					(size 1 1)
					(thickness 0.15)
				)
			)
		)
		(property "Val" "22u"
			(at 374.168501 -8.322501 0)
			(layer "F.Fab")
			(hide yes)
			(effects
				(font
					(size 1 1)
					(thickness 0.15)
				)
			)
		)
		(property "Voltage" ""
			(at 374.168501 -8.322501 0)
			(layer "F.Fab")
			(hide yes)
			(effects
				(font
					(size 1 1)
					(thickness 0.15)
				)
			)
		)
		(sheetname "/Supply/")
		(sheetfile "supply.kicad_sch")
		(attr smd)
		(fp_line
			(start -0.3 -0.3)
			(end 0.3 -0.3)
			(stroke
				(width 0.15)
				(type solid)
			)
			(layer "F.SilkS")
		)
		(fp_line
			(start -0.3 0.3)
			(end 0.3 0.3)
			(stroke
				(width 0.15)
				(type solid)
			)
			(layer "F.SilkS")
		)
		(fp_rect
			(start -1.24 -0.7)
			(end 1.24 0.7)
			(stroke
				(width 0.05)
				(type solid)
			)
			(fill no)
			(layer "F.CrtYd")
		)
		(fp_rect
			(start -0.8 -0.4)
			(end 0.8 0.4)
			(stroke
				(width 0.15)
				(type solid)
			)
			(fill no)
			(layer "F.Fab")
		)
		(pad "1" smd roundrect
			(at -0.7 0 90)
			(size 0.6 0.8)
			(layers "F.Cu" "F.Mask" "F.Paste")
			(roundrect_rratio 0.2)
			(net 1 "GND")
			(pintype "passive")
		)
		(pad "2" smd roundrect
			(at 0.7 0 90)
			(size 0.6 0.8)
			(layers "F.Cu" "F.Mask" "F.Paste")
			(roundrect_rratio 0.2)
			(net 51 "/Supply/1V8_local")
			(pintype "passive")
		)
	)
	(footprint "antmicro-footprints:R_0402_1005Metric"
		(layer "F.Cu")
		(at 122.85 186.6 -90)
		(descr "Resistor SMD 0402")
		(tags "resistor SMD 0402")
		(property "Reference" "R8"
			(at -1.122484 -0.772697 270)
			(layer "F.SilkS")
			(hide yes)
			(effects
				(font
					(size 0.7 0.7)
					(thickness 0.15)
				)
				(justify left bottom)
			)
		)
		(property "Value" "R_22R_0402"
			(at -1.011843 1.772047 270)
			(layer "F.Fab")
			(effects
				(font
					(size 0.7 0.7)
					(thickness 0.15)
				)
				(justify left bottom)
			)
		)
		(property "Datasheet" "https://www.bourns.com/docs/product-datasheets/cr.pdf"
			(at 0 0 270)
			(layer "F.Fab")
			(hide yes)
			(effects
				(font
					(size 1.27 1.27)
					(thickness 0.15)
				)
			)
		)
		(property "Author" "Antmicro"
			(at -63.75 309.45 0)
			(layer "F.Fab")
			(hide yes)
			(effects
				(font
					(size 1 1)
					(thickness 0.15)
				)
			)
		)
		(property "License" "Apache-2.0"
			(at -63.75 309.45 0)
			(layer "F.Fab")
			(hide yes)
			(effects
				(font
					(size 1 1)
					(thickness 0.15)
				)
			)
		)
		(property "MPN" "CR0402-FX-22R0GLF"
			(at -63.75 309.45 0)
			(layer "F.Fab")
			(hide yes)
			(effects
				(font
					(size 1 1)
					(thickness 0.15)
				)
			)
		)
		(property "Manufacturer" "Bourns"
			(at -63.75 309.45 0)
			(layer "F.Fab")
			(hide yes)
			(effects
				(font
					(size 1 1)
					(thickness 0.15)
				)
			)
		)
		(property "Tolerance" "1%"
			(at -63.75 309.45 0)
			(layer "F.Fab")
			(hide yes)
			(effects
				(font
					(size 1 1)
					(thickness 0.15)
				)
			)
		)
		(property "Val" "22R"
			(at -63.75 309.45 0)
			(layer "F.Fab")
			(hide yes)
			(effects
				(font
					(size 1 1)
					(thickness 0.15)
				)
			)
		)
		(sheetname "/HyperRAM + QSPI Flash/")
		(sheetfile "hyperram-flash.kicad_sch")
		(attr smd)
		(fp_rect
			(start -0.93 -0.47)
			(end 0.93 0.47)
			(stroke
				(width 0.05)
				(type solid)
			)
			(fill no)
			(layer "F.CrtYd")
		)
		(fp_rect
			(start -0.5 -0.25)
			(end 0.5 0.25)
			(stroke
				(width 0.15)
				(type solid)
			)
			(fill no)
			(layer "F.Fab")
		)
		(pad "1" smd roundrect
			(at -0.485 0 270)
			(size 0.59 0.64)
			(layers "F.Cu" "F.Mask" "F.Paste")
			(roundrect_rratio 0.25)
			(net 361 "/HyperRAM + QSPI Flash/IO2")
			(pintype "passive")
		)
		(pad "2" smd roundrect
			(at 0.485 0 270)
			(size 0.59 0.64)
			(layers "F.Cu" "F.Mask" "F.Paste")
			(roundrect_rratio 0.25)
			(net 628 "/FPGA Config/FLASH.IO2")
			(pintype "passive")
		)
	)
	(footprint "antmicro-footprints:TP_SMD_1mm"
		(layer "F.Cu")
		(at 199.2 141.2)
		(property "Reference" "TP19"
			(at 0 -0.731898 0)
			(layer "F.SilkS")
			(hide yes)
			(effects
				(font
					(size 0.7 0.7)
					(thickness 0.15)
				)
				(justify left bottom)
			)
		)
		(property "Value" "TP_1mm_SMD"
			(at 0 1.4 0)
			(layer "F.Fab")
			(effects
				(font
					(size 0.7 0.7)
					(thickness 0.15)
				)
				(justify left bottom)
			)
		)
		(property "Author" "Antmicro"
			(at 0 0 0)
			(layer "F.Fab")
			(hide yes)
			(effects
				(font
					(size 1 1)
					(thickness 0.15)
				)
			)
		)
		(property "License" "Apache-2.0"
			(at 0 0 0)
			(layer "F.Fab")
			(hide yes)
			(effects
				(font
					(size 1 1)
					(thickness 0.15)
				)
			)
		)
		(property "MPN" ""
			(at 0 0 0)
			(layer "F.Fab")
			(hide yes)
			(effects
				(font
					(size 1 1)
					(thickness 0.15)
				)
			)
		)
		(property "Manufacturer" ""
			(at 0 0 0)
			(layer "F.Fab")
			(hide yes)
			(effects
				(font
					(size 1 1)
					(thickness 0.15)
				)
			)
		)
		(sheetname "/Supply/")
		(sheetfile "supply.kicad_sch")
		(attr exclude_from_pos_files)
		(pad "1" smd circle
			(at 0 0)
			(size 1 1)
			(layers "F.Cu" "F.Mask")
			(net 41 "+3V3_AON")
			(pinfunction "1")
			(pintype "passive")
		)
	)
)
